(kicad_pcb
	(version 20260206)
	(generator "pcbnew")
	(generator_version "10.0")
	(general
		(thickness 1.6)
		(legacy_teardrops no)
	)
	(paper "A4")
	(title_block
		(title "v1-tray-backplane — T6M_tray_BP_c_1023_1120.brd")
		(comment 1 "Open CloudServer (Microsoft) / footprints 32-34 of 170")
	)
	(layers
		(0 "F.Cu" signal "TOP")
		(4 "In1.Cu" signal "GND")
		(6 "In2.Cu" signal "IN1")
		(8 "In3.Cu" signal "VCC")
		(10 "In4.Cu" signal "VCC1")
		(12 "In5.Cu" signal "IN2")
		(14 "In6.Cu" signal "GND1")
		(2 "B.Cu" signal "BOTTOM")
		(9 "F.Adhes" user "F.Adhesive")
		(11 "B.Adhes" user "B.Adhesive")
		(13 "F.Paste" user "Package Geometry/Pastemask Top")
		(15 "B.Paste" user "Package Geometry/Pastemask Bottom")
		(5 "F.SilkS" user "Ref Des/Silkscreen Top")
		(7 "B.SilkS" user "Ref Des/Silkscreen Bottom")
		(1 "F.Mask" user "Board Geometry/Soldermask Top")
		(3 "B.Mask" user "Board Geometry/Soldermask Bottom")
		(17 "Dwgs.User" user "User.Drawings")
		(19 "Cmts.User" user "User.Comments")
		(21 "Eco1.User" user "User.Eco1")
		(23 "Eco2.User" user "User.Eco2")
		(25 "Edge.Cuts" user "Board Geometry/Outline")
		(27 "Margin" user)
		(31 "F.CrtYd" user "Package Geometry/Place Bound Top")
		(29 "B.CrtYd" user "Package Geometry/Place Bound Bottom")
		(35 "F.Fab" user "Ref Des/Assembly Top")
		(33 "B.Fab" user "Ref Des/Assembly Bottom")
	)
	(footprint ""
		(layer "F.Cu")
		(at 345.425268 -21.674582 90)
		(property "Reference" "R60"
			(at 3.336036 -56.962548 90)
			(unlocked yes)
			(layer "F.SilkS")
			(effects
				(font
					(size 0.7874 0.5842)
					(thickness 0.1524)
				)
				(justify left)
			)
		)
		(property "Value" ""
			(at 0 0 90)
			(layer "F.Fab")
			(effects
				(font
					(size 1.27 1.27)
				)
			)
		)
		(duplicate_pad_numbers_are_jumpers no)
		(fp_line
			(start 0.7874 -0.4064)
			(end 0.7874 0.4064)
			(stroke
				(width 0.1524)
				(type default)
			)
			(layer "F.SilkS")
		)
		(fp_line
			(start -0.7874 -0.4064)
			(end 0.7874 -0.4064)
			(stroke
				(width 0.1524)
				(type default)
			)
			(layer "F.SilkS")
		)
		(fp_line
			(start 0.7874 0.4064)
			(end -0.7874 0.4064)
			(stroke
				(width 0.1524)
				(type default)
			)
			(layer "F.SilkS")
		)
		(fp_line
			(start -0.7874 0.4064)
			(end -0.7874 -0.4064)
			(stroke
				(width 0.1524)
				(type default)
			)
			(layer "F.SilkS")
		)
		(fp_poly
			(pts
				(xy -0.508 0.2794) (xy -0.508 0.2286) (xy -0.635 0.2286) (xy -0.635 -0.254) (xy -0.5334 -0.254)
				(xy -0.5334 -0.2794) (xy 0.5334 -0.2794) (xy 0.5334 -0.254) (xy 0.635 -0.254) (xy 0.635 0.254) (xy 0.5334 0.254)
				(xy 0.5334 0.2794)
			)
			(stroke
				(width 0)
				(type default)
			)
			(fill no)
			(layer "F.CrtYd")
		)
		(pad "1" smd rect
			(at 0.40005 0 90)
			(size 0.4572 0.508)
			(layers "F.Cu" "F.Mask" "F.Paste")
			(net "GND")
		)
		(pad "2" smd rect
			(at -0.40005 0 90)
			(size 0.4572 0.508)
			(layers "F.Cu" "F.Mask" "F.Paste")
			(net "SKU_PIN_BLAD2_2")
		)
	)
	(footprint ""
		(layer "F.Cu")
		(at 412.494984 -28.4099 180)
		(property "Reference" "U2"
			(at -7.495032 -9.687052 0)
			(unlocked yes)
			(layer "F.SilkS")
			(effects
				(font
					(size 0.7874 0.5842)
					(thickness 0.1524)
				)
				(justify left)
			)
		)
		(property "Value" ""
			(at 0 0 180)
			(layer "F.Fab")
			(effects
				(font
					(size 1.27 1.27)
				)
			)
		)
		(duplicate_pad_numbers_are_jumpers no)
		(fp_line
			(start 6.949948 8.32993)
			(end 6.949948 5.7912)
			(stroke
				(width 0.1524)
				(type default)
			)
			(layer "F.SilkS")
		)
		(fp_line
			(start 6.949948 4.572)
			(end 6.949948 0)
			(stroke
				(width 0.1524)
				(type default)
			)
			(layer "F.SilkS")
		)
		(fp_line
			(start 6.949948 0)
			(end 6.949948 -3.670046)
			(stroke
				(width 0.1524)
				(type default)
			)
			(layer "F.SilkS")
		)
		(fp_line
			(start 6.949948 -3.670046)
			(end 0 -3.670046)
			(stroke
				(width 0.1524)
				(type default)
			)
			(layer "F.SilkS")
		)
		(fp_line
			(start 0 -3.670046)
			(end -6.949948 -3.670046)
			(stroke
				(width 0.1524)
				(type default)
			)
			(layer "F.SilkS")
		)
		(fp_line
			(start -6.949948 8.32993)
			(end 6.949948 8.32993)
			(stroke
				(width 0.1524)
				(type default)
			)
			(layer "F.SilkS")
		)
		(fp_line
			(start -6.949948 5.7912)
			(end -6.949948 8.32993)
			(stroke
				(width 0.1524)
				(type default)
			)
			(layer "F.SilkS")
		)
		(fp_line
			(start -6.949948 0)
			(end -6.949948 4.5466)
			(stroke
				(width 0.1524)
				(type default)
			)
			(layer "F.SilkS")
		)
		(fp_line
			(start -6.949948 -3.670046)
			(end -6.949948 0)
			(stroke
				(width 0.1524)
				(type default)
			)
			(layer "F.SilkS")
		)
		(fp_poly
			(pts
				(xy -12.923266 -1.944878) (xy -14.898878 -2.483612) (xy -13.462 -3.92049)
			)
			(stroke
				(width 0)
				(type default)
			)
			(fill yes)
			(layer "F.SilkS")
		)
		(fp_poly
			(pts
				(arc
					(start 4.933188 5.180076)
					(mid 7.066788 5.180076)
					(end 4.933188 5.180076)
				)
			)
			(stroke
				(width 0)
				(type default)
			)
			(fill no)
			(layer "B.CrtYd")
		)
		(fp_poly
			(pts
				(arc
					(start -7.06755 5.180076)
					(mid -4.932426 5.180076)
					(end -7.06755 5.180076)
				)
			)
			(stroke
				(width 0)
				(type default)
			)
			(fill no)
			(layer "B.CrtYd")
		)
		(fp_poly
			(pts
				(xy -6.949948 8.32993) (xy 6.949948 8.32993) (xy 6.949948 -3.670046) (xy -6.949948 -3.670046)
			)
			(stroke
				(width 0)
				(type default)
			)
			(fill no)
			(layer "F.CrtYd")
		)
		(fp_line
			(start 6.949948 8.32993)
			(end 6.949948 -3.670046)
			(stroke
				(width 0.1)
				(type default)
			)
			(layer "F.Fab")
		)
		(fp_line
			(start 6.949948 -3.670046)
			(end -6.949948 -3.670046)
			(stroke
				(width 0.1)
				(type default)
			)
			(layer "F.Fab")
		)
		(fp_line
			(start -6.700012 0)
			(end -6.949948 0)
			(stroke
				(width 0.1)
				(type default)
			)
			(layer "F.Fab")
		)
		(fp_line
			(start -6.949948 8.32993)
			(end 6.949948 8.32993)
			(stroke
				(width 0.1)
				(type default)
			)
			(layer "F.Fab")
		)
		(fp_line
			(start -6.949948 0)
			(end -6.949948 8.32993)
			(stroke
				(width 0.1)
				(type default)
			)
			(layer "F.Fab")
		)
		(fp_line
			(start -6.949948 -3.670046)
			(end -6.949948 0)
			(stroke
				(width 0.1)
				(type default)
			)
			(layer "F.Fab")
		)
		(fp_poly
			(pts
				(xy -6.9596 0) (xy -8.7376 1.016) (xy -8.7376 -1.016)
			)
			(stroke
				(width 0)
				(type default)
			)
			(fill yes)
			(layer "F.Fab")
		)
		(fp_text user "A13"
			(at 6.353302 -9.204452 0)
			(unlocked yes)
			(layer "F.SilkS")
			(effects
				(font
					(size 0.7874 0.5842)
					(thickness 0.1524)
				)
				(justify left)
			)
		)
		(fp_text user "B13"
			(at 6.353302 -10.225278 0)
			(unlocked yes)
			(layer "F.SilkS")
			(effects
				(font
					(size 0.7874 0.5842)
					(thickness 0.1524)
				)
				(justify left)
			)
		)
		(fp_text user "A1"
			(at -11.610848 -3.845052 0)
			(unlocked yes)
			(layer "F.SilkS")
			(effects
				(font
					(size 0.7874 0.5842)
					(thickness 0.1524)
				)
				(justify left)
			)
		)
		(fp_text user "B1"
			(at -11.763248 -6.288278 0)
			(unlocked yes)
			(layer "F.SilkS")
			(effects
				(font
					(size 0.7874 0.5842)
					(thickness 0.1524)
				)
				(justify left)
			)
		)
		(fp_text user "A13"
			(at 7.360666 -0.091948 180)
			(unlocked yes)
			(layer "F.Fab")
			(effects
				(font
					(size 0.7874 0.5842)
					(thickness 0.000001)
				)
				(justify left)
			)
		)
		(fp_text user "B13"
			(at 7.360666 -2.601722 180)
			(unlocked yes)
			(layer "F.Fab")
			(effects
				(font
					(size 0.7874 0.5842)
					(thickness 0.000001)
				)
				(justify left)
			)
		)
		(fp_text user "A1"
			(at -8.609584 1.330452 180)
			(unlocked yes)
			(layer "F.Fab")
			(effects
				(font
					(size 0.7874 0.5842)
					(thickness 0.000001)
				)
				(justify left)
			)
		)
		(fp_text user "B1"
			(at -8.685784 -2.601722 180)
			(unlocked yes)
			(layer "F.Fab")
			(effects
				(font
					(size 0.7874 0.5842)
					(thickness 0.000001)
				)
				(justify left)
			)
		)
		(pad "" np_thru_hole circle
			(at -5.999988 5.180076 180)
			(size 1.6002 1.6002)
			(drill 1.6002)
			(layers "*.Cu" "*.Mask")
			(clearance 0.381)
			(thermal_gap 0.381)
		)
		(pad "" np_thru_hole circle
			(at 5.999988 5.180076 180)
			(size 1.6002 1.6002)
			(drill 1.6002)
			(layers "*.Cu" "*.Mask")
			(clearance 0.381)
			(thermal_gap 0.381)
		)
		(pad "A1" smd rect
			(at -4.59994 0 180)
			(size 0.381 1.8542)
			(layers "F.Cu" "F.Mask" "F.Paste")
			(net "GND")
		)
		(pad "A2" smd rect
			(at -3.800094 0 180)
			(size 0.381 1.8542)
			(layers "F.Cu" "F.Mask" "F.Paste")
			(net "SAS_BLAD2_RX1_P")
		)
		(pad "A3" smd rect
			(at -2.999994 0 180)
			(size 0.381 1.8542)
			(layers "F.Cu" "F.Mask" "F.Paste")
			(net "SAS_BLAD2_RX1_N")
		)
		(pad "A4" smd rect
			(at -2.199894 0 180)
			(size 0.381 1.8542)
			(layers "F.Cu" "F.Mask" "F.Paste")
			(net "GND")
		)
		(pad "A5" smd rect
			(at -1.400048 0 180)
			(size 0.381 1.8542)
			(layers "F.Cu" "F.Mask" "F.Paste")
			(net "SAS_BLAD2_RX2_P")
		)
		(pad "A6" smd rect
			(at -0.599948 0 180)
			(size 0.381 1.8542)
			(layers "F.Cu" "F.Mask" "F.Paste")
			(net "SAS_BLAD2_RX2_N")
		)
		(pad "A7" smd rect
			(at 0.199898 0 180)
			(size 0.381 1.8542)
			(layers "F.Cu" "F.Mask" "F.Paste")
			(net "GND")
		)
		(pad "A8" smd rect
			(at 0.999998 0 180)
			(size 0.381 1.8542)
			(layers "F.Cu" "F.Mask" "F.Paste")
			(net "SAS_BLAD2_RX3_P")
		)
		(pad "A9" smd rect
			(at 1.800098 0 180)
			(size 0.381 1.8542)
			(layers "F.Cu" "F.Mask" "F.Paste")
			(net "SAS_BLAD2_RX3_N")
		)
		(pad "A10" smd rect
			(at 2.599944 0 180)
			(size 0.381 1.8542)
			(layers "F.Cu" "F.Mask" "F.Paste")
			(net "GND")
		)
		(pad "A11" smd rect
			(at 3.400044 0 180)
			(size 0.381 1.8542)
			(layers "F.Cu" "F.Mask" "F.Paste")
			(net "SAS_BLAD2_RX4_P")
		)
		(pad "A12" smd rect
			(at 4.19989 0 180)
			(size 0.381 1.8542)
			(layers "F.Cu" "F.Mask" "F.Paste")
			(net "SAS_BLAD2_RX4_N")
		)
		(pad "A13" smd rect
			(at 4.99999 0 180)
			(size 0.381 1.8542)
			(layers "F.Cu" "F.Mask" "F.Paste")
			(net "GND")
		)
		(pad "B1" smd rect
			(at -4.99999 -2.510028 180)
			(size 0.381 1.8542)
			(layers "F.Cu" "F.Mask" "F.Paste")
			(net "GND")
		)
		(pad "B2" smd rect
			(at -4.19989 -2.510028 180)
			(size 0.381 1.8542)
			(layers "F.Cu" "F.Mask" "F.Paste")
			(net "SAS_BLAD2_TX1_P")
		)
		(pad "B3" smd rect
			(at -3.400044 -2.510028 180)
			(size 0.381 1.8542)
			(layers "F.Cu" "F.Mask" "F.Paste")
			(net "SAS_BLAD2_TX1_N")
		)
		(pad "B4" smd rect
			(at -2.599944 -2.510028 180)
			(size 0.381 1.8542)
			(layers "F.Cu" "F.Mask" "F.Paste")
			(net "GND")
		)
		(pad "B5" smd rect
			(at -1.800098 -2.510028 180)
			(size 0.381 1.8542)
			(layers "F.Cu" "F.Mask" "F.Paste")
			(net "SAS_BLAD2_TX2_P")
		)
		(pad "B6" smd rect
			(at -0.999998 -2.510028 180)
			(size 0.381 1.8542)
			(layers "F.Cu" "F.Mask" "F.Paste")
			(net "SAS_BLAD2_TX2_N")
		)
		(pad "B7" smd rect
			(at -0.199898 -2.510028 180)
			(size 0.381 1.8542)
			(layers "F.Cu" "F.Mask" "F.Paste")
			(net "GND")
		)
		(pad "B8" smd rect
			(at 0.599948 -2.510028 180)
			(size 0.381 1.8542)
			(layers "F.Cu" "F.Mask" "F.Paste")
			(net "SAS_BLAD2_TX3_P")
		)
		(pad "B9" smd rect
			(at 1.400048 -2.510028 180)
			(size 0.381 1.8542)
			(layers "F.Cu" "F.Mask" "F.Paste")
			(net "SAS_BLAD2_TX3_N")
		)
		(pad "B10" smd rect
			(at 2.199894 -2.510028 180)
			(size 0.381 1.8542)
			(layers "F.Cu" "F.Mask" "F.Paste")
			(net "GND")
		)
		(pad "B11" smd rect
			(at 2.999994 -2.510028 180)
			(size 0.381 1.8542)
			(layers "F.Cu" "F.Mask" "F.Paste")
			(net "SAS_BLAD2_TX4_P")
		)
		(pad "B12" smd rect
			(at 3.800094 -2.510028 180)
			(size 0.381 1.8542)
			(layers "F.Cu" "F.Mask" "F.Paste")
			(net "SAS_BLAD2_TX4_N")
		)
		(pad "B13" smd rect
			(at 4.59994 -2.510028 180)
			(size 0.381 1.8542)
			(layers "F.Cu" "F.Mask" "F.Paste")
			(net "GND")
		)
		(zone
			(layer "F.Cu")
			(hatch none 0.5)
			(connect_pads
				(clearance 0)
			)
			(min_thickness 0.25)
			(keepout
				(tracks not_allowed)
				(vias allowed)
				(pads allowed)
				(copperpour not_allowed)
				(footprints allowed)
			)
			(placement
				(enabled no)
				(sheetname "")
			)
			(fill
				(thermal_gap 0.5)
				(thermal_bridge_width 0.5)
				(island_removal_mode 0)
			)
			(polygon
				(pts
					(xy 407.414984 -36.73983) (xy 405.575008 -36.73983) (xy 405.575008 -35.279838) (xy 407.414984 -35.279838)
				)
			)
		)
		(zone
			(layer "F.Cu")
			(hatch none 0.5)
			(connect_pads
				(clearance 0)
			)
			(min_thickness 0.25)
			(keepout
				(tracks not_allowed)
				(vias allowed)
				(pads allowed)
				(copperpour not_allowed)
				(footprints allowed)
			)
			(placement
				(enabled no)
				(sheetname "")
			)
			(fill
				(thermal_gap 0.5)
				(thermal_bridge_width 0.5)
				(island_removal_mode 0)
			)
			(polygon
				(pts
					(xy 419.41496 -36.73983) (xy 417.574984 -36.73983) (xy 417.574984 -35.279838) (xy 419.41496 -35.279838)
				)
			)
		)
		(zone
			(layers "F.Cu" "B.Cu" "In1.Cu" "In2.Cu" "In3.Cu" "In4.Cu" "In5.Cu" "In6.Cu")
			(hatch none 0.5)
			(connect_pads
				(clearance 0)
			)
			(min_thickness 0.25)
			(keepout
				(tracks not_allowed)
				(vias allowed)
				(pads allowed)
				(copperpour not_allowed)
				(footprints allowed)
			)
			(placement
				(enabled no)
				(sheetname "")
			)
			(fill
				(thermal_gap 0.5)
				(thermal_bridge_width 0.5)
				(island_removal_mode 0)
			)
			(polygon
				(pts
					(arc
						(start 407.713942 -33.589976)
						(mid 405.27605 -33.589976)
						(end 407.713942 -33.589976)
					)
				)
			)
		)
		(zone
			(layers "F.Cu" "B.Cu" "In1.Cu" "In2.Cu" "In3.Cu" "In4.Cu" "In5.Cu" "In6.Cu")
			(hatch none 0.5)
			(connect_pads
				(clearance 0)
			)
			(min_thickness 0.25)
			(keepout
				(tracks not_allowed)
				(vias allowed)
				(pads allowed)
				(copperpour not_allowed)
				(footprints allowed)
			)
			(placement
				(enabled no)
				(sheetname "")
			)
			(fill
				(thermal_gap 0.5)
				(thermal_bridge_width 0.5)
				(island_removal_mode 0)
			)
			(polygon
				(pts
					(arc
						(start 419.71468 -33.589976)
						(mid 417.275264 -33.589976)
						(end 419.71468 -33.589976)
					)
				)
			)
		)
	)
	(footprint ""
		(layer "F.Cu")
		(at 298.920154 -10.6299)
		(property "Reference" "J5"
			(at -5.4102 -11.267948 0)
			(unlocked yes)
			(layer "F.SilkS")
			(effects
				(font
					(size 0.7874 0.5842)
					(thickness 0.1524)
				)
				(justify left)
			)
		)
		(property "Value" ""
			(at 0 0 0)
			(layer "F.Fab")
			(effects
				(font
					(size 1.27 1.27)
				)
			)
		)
		(duplicate_pad_numbers_are_jumpers no)
		(fp_line
			(start -5.32511 -10.500106)
			(end -5.32511 0)
			(stroke
				(width 0.1524)
				(type default)
			)
			(layer "F.SilkS")
		)
		(fp_line
			(start -5.32511 0)
			(end -5.32511 43.029886)
			(stroke
				(width 0.1524)
				(type default)
			)
			(layer "F.SilkS")
		)
		(fp_line
			(start -5.32511 13.129768)
			(end 5.32511 13.129768)
			(stroke
				(width 0.1524)
				(type default)
			)
			(layer "F.SilkS")
		)
		(fp_line
			(start -5.32511 43.029886)
			(end 5.32511 43.029886)
			(stroke
				(width 0.1524)
				(type default)
			)
			(layer "F.SilkS")
		)
		(fp_line
			(start 5.32511 -10.500106)
			(end -5.32511 -10.500106)
			(stroke
				(width 0.1524)
				(type default)
			)
			(layer "F.SilkS")
		)
		(fp_line
			(start 5.32511 43.029886)
			(end 5.32511 -10.500106)
			(stroke
				(width 0.1524)
				(type default)
			)
			(layer "F.SilkS")
		)
		(fp_poly
			(pts
				(xy -7.86638 -0.8636) (xy -7.86638 0.9398) (xy -7.86638 0.951484) (xy -6.11378 0)
			)
			(stroke
				(width 0)
				(type default)
			)
			(fill yes)
			(layer "F.SilkS")
		)
		(fp_poly
			(pts
				(arc
					(start 2.758694 0)
					(mid -2.758694 0)
					(end 2.758694 0)
				)
			)
			(stroke
				(width 0)
				(type default)
			)
			(fill no)
			(layer "B.CrtYd")
		)
		(fp_poly
			(pts
				(arc
					(start 2.758694 5.62991)
					(mid -2.758694 5.62991)
					(end 2.758694 5.62991)
				)
			)
			(stroke
				(width 0)
				(type default)
			)
			(fill no)
			(layer "B.CrtYd")
		)
		(fp_poly
			(pts
				(arc
					(start 2.95275 -6.620002)
					(mid -2.95275 -6.620002)
					(end 2.95275 -6.620002)
				)
			)
			(stroke
				(width 0)
				(type default)
			)
			(fill no)
			(layer "B.CrtYd")
		)
		(fp_poly
			(pts
				(xy -5.32511 0) (xy -5.32511 43.029886) (xy 5.32511 43.029886) (xy 5.32511 -10.500106) (xy -5.32511 -10.500106)
			)
			(stroke
				(width 0)
				(type default)
			)
			(fill no)
			(layer "F.CrtYd")
		)
		(fp_line
			(start -5.32511 -10.500106)
			(end -5.32511 0)
			(stroke
				(width 0.1)
				(type default)
			)
			(layer "F.Fab")
		)
		(fp_line
			(start -5.32511 0)
			(end -5.32511 43.029886)
			(stroke
				(width 0.1)
				(type default)
			)
			(layer "F.Fab")
		)
		(fp_line
			(start -5.32511 13.129768)
			(end 5.32511 13.129768)
			(stroke
				(width 0.1)
				(type default)
			)
			(layer "F.Fab")
		)
		(fp_line
			(start -5.32511 43.029886)
			(end 5.32511 43.029886)
			(stroke
				(width 0.1)
				(type default)
			)
			(layer "F.Fab")
		)
		(fp_line
			(start 5.32511 -10.500106)
			(end -5.32511 -10.500106)
			(stroke
				(width 0.1)
				(type default)
			)
			(layer "F.Fab")
		)
		(fp_line
			(start 5.32511 43.029886)
			(end 5.32511 -10.500106)
			(stroke
				(width 0.1)
				(type default)
			)
			(layer "F.Fab")
		)
		(fp_poly
			(pts
				(xy -7.86638 -0.8636) (xy -7.86638 0.9398) (xy -7.86638 0.951484) (xy -6.11378 0)
			)
			(stroke
				(width 0)
				(type default)
			)
			(fill yes)
			(layer "F.Fab")
		)
		(fp_text user "1"
			(at -6.031484 -0.039116 0)
			(unlocked yes)
			(layer "F.SilkS")
			(effects
				(font
					(size 0.7874 0.5842)
					(thickness 0.1524)
				)
				(justify left)
			)
		)
		(fp_text user "1"
			(at -2.9464 0.043688 0)
			(unlocked yes)
			(layer "B.SilkS")
			(effects
				(font
					(size 0.7874 0.5842)
					(thickness 0.1524)
				)
				(justify left mirror)
			)
		)
		(fp_text user "1"
			(at -2.9464 0.043688 0)
			(unlocked yes)
			(layer "B.Fab")
			(effects
				(font
					(size 0.7874 0.5842)
					(thickness 0.000001)
				)
				(justify left mirror)
			)
		)
		(fp_text user "1"
			(at -6.031484 -0.039116 0)
			(unlocked yes)
			(layer "F.Fab")
			(effects
				(font
					(size 0.7874 0.5842)
					(thickness 0.000001)
				)
				(justify left)
			)
		)
		(pad "1" thru_hole circle
			(at 0 0)
			(size 5.4102 5.4102)
			(drill 4.0132)
			(layers "*.Cu" "*.Mask")
			(remove_unused_layers no)
			(net "GND")
			(clearance -0.4445)
		)
		(pad "2" thru_hole circle
			(at 0 5.62991)
			(size 5.4102 5.4102)
			(drill 4.0132)
			(layers "*.Cu" "*.Mask")
			(remove_unused_layers no)
			(net "GND")
			(clearance -0.4445)
		)
		(pad "3" thru_hole circle
			(at 0 -6.620002)
			(size 5.7912 5.7912)
			(drill 4.0132)
			(layers "*.Cu" "*.Mask")
			(remove_unused_layers no)
			(net "GND")
			(clearance -0.635)
		)
	)
)
